# SCM (Grand Teton) — schematic netlist excerpt (pin names and nets, part order shuffled) for the footprints in the layout excerpt that follows; sources: Cadence DE-HDL packaged netlist, KiCad conversion of 12092022_DA0F0TMDCD0_F0T_Management_Board_D_brd_V3_OCP.brd

R305  Q_RES  0 5% CHIP  pkg 0402LF  page 41 : A = P3V3_AUX ; B = VCCIO0
R194  Q_RES  1K 1% CHIP  pkg 0402LF  page 14 : A = P1V2_P1V0_I3C_VDDL1 ; B = I3C1_SPD_SCL

(kicad_pcb
	(version 20260206)
	(generator "pcbnew")
	(generator_version "10.0")
	(general
		(thickness 1.6)
		(legacy_teardrops no)
	)
	(paper "A4")
	(title_block
		(title "12092022_DA0F0TMDCD0_F0T_Management_Board_D_brd_V3_OCP.brd")
		(comment 1 "Grand Teton / footprints 1209-1210 of 1440")
	)
	(layers
		(0 "F.Cu" signal "TOP")
		(4 "In1.Cu" signal "GND")
		(6 "In2.Cu" signal "IN1")
		(8 "In3.Cu" signal "GND1")
		(10 "In4.Cu" signal "IN2")
		(12 "In5.Cu" signal "VCC")
		(14 "In6.Cu" signal "VCC1")
		(16 "In7.Cu" signal "IN3")
		(18 "In8.Cu" signal "GND2")
		(20 "In9.Cu" signal "IN4")
		(22 "In10.Cu" signal "GND3")
		(2 "B.Cu" signal "BOTTOM")
		(9 "F.Adhes" user "F.Adhesive")
		(11 "B.Adhes" user "B.Adhesive")
		(13 "F.Paste" user "Package Geometry/Pastemask Top")
		(15 "B.Paste" user "Package Geometry/Pastemask Bottom")
		(5 "F.SilkS" user "Ref Des/Silkscreen Top")
		(7 "B.SilkS" user "Ref Des/Silkscreen Bottom")
		(1 "F.Mask" user "Board Geometry/Soldermask Top")
		(3 "B.Mask" user "Board Geometry/Soldermask Bottom")
		(17 "Dwgs.User" user "User.Drawings")
		(19 "Cmts.User" user "User.Comments")
		(21 "Eco1.User" user "User.Eco1")
		(23 "Eco2.User" user "User.Eco2")
		(25 "Edge.Cuts" user "Board Geometry/Outline")
		(27 "Margin" user)
		(31 "F.CrtYd" user "Package Geometry/Place Bound Top")
		(29 "B.CrtYd" user "Package Geometry/Place Bound Bottom")
		(35 "F.Fab" user "Ref Des/Assembly Top")
		(33 "B.Fab" user "Ref Des/Assembly Bottom")
	)
	(footprint ""
		(layer "B.Cu")
		(at 25.019 -91.44)
		(property "Reference" "R305"
			(at 0 0 0)
			(layer "B.SilkS")
			(hide yes)
			(effects
				(font
					(size 1.27 1.27)
				)
				(justify mirror)
			)
		)
		(property "Value" ""
			(at 0 0 0)
			(layer "B.Fab")
			(effects
				(font
					(size 1.27 1.27)
				)
				(justify mirror)
			)
		)
		(duplicate_pad_numbers_are_jumpers no)
		(fp_line
			(start -0.7874 -0.4064)
			(end -0.7874 0.4064)
			(stroke
				(width 0.1524)
				(type default)
			)
			(layer "B.SilkS")
		)
		(fp_line
			(start -0.7874 0.4064)
			(end 0.7874 0.4064)
			(stroke
				(width 0.1524)
				(type default)
			)
			(layer "B.SilkS")
		)
		(fp_line
			(start 0.7874 -0.4064)
			(end -0.7874 -0.4064)
			(stroke
				(width 0.1524)
				(type default)
			)
			(layer "B.SilkS")
		)
		(fp_line
			(start 0.7874 0.4064)
			(end 0.7874 -0.4064)
			(stroke
				(width 0.1524)
				(type default)
			)
			(layer "B.SilkS")
		)
		(fp_line
			(start -0.67945 -0.3048)
			(end -0.67945 0.3048)
			(stroke
				(width 0.1)
				(type default)
			)
			(layer "B.Fab")
		)
		(fp_line
			(start -0.67945 0.3048)
			(end -0.120396 0.3048)
			(stroke
				(width 0.1)
				(type default)
			)
			(layer "B.Fab")
		)
		(fp_line
			(start -0.12065 -0.3048)
			(end -0.67945 -0.3048)
			(stroke
				(width 0.1)
				(type default)
			)
			(layer "B.Fab")
		)
		(fp_line
			(start -0.12065 -0.2794)
			(end -0.12065 -0.3048)
			(stroke
				(width 0.1)
				(type default)
			)
			(layer "B.Fab")
		)
		(fp_line
			(start -0.120396 0.2794)
			(end 0.12065 0.2794)
			(stroke
				(width 0.1)
				(type default)
			)
			(layer "B.Fab")
		)
		(fp_line
			(start -0.120396 0.3048)
			(end -0.120396 0.2794)
			(stroke
				(width 0.1)
				(type default)
			)
			(layer "B.Fab")
		)
		(fp_line
			(start 0.12065 -0.305054)
			(end 0.12065 -0.2794)
			(stroke
				(width 0.1)
				(type default)
			)
			(layer "B.Fab")
		)
		(fp_line
			(start 0.12065 -0.2794)
			(end -0.12065 -0.2794)
			(stroke
				(width 0.1)
				(type default)
			)
			(layer "B.Fab")
		)
		(fp_line
			(start 0.12065 0.2794)
			(end 0.12065 0.3048)
			(stroke
				(width 0.1)
				(type default)
			)
			(layer "B.Fab")
		)
		(fp_line
			(start 0.12065 0.3048)
			(end 0.67945 0.3048)
			(stroke
				(width 0.1)
				(type default)
			)
			(layer "B.Fab")
		)
		(fp_line
			(start 0.67945 -0.305054)
			(end 0.12065 -0.305054)
			(stroke
				(width 0.1)
				(type default)
			)
			(layer "B.Fab")
		)
		(fp_line
			(start 0.67945 0.3048)
			(end 0.67945 -0.305054)
			(stroke
				(width 0.1)
				(type default)
			)
			(layer "B.Fab")
		)
		(pad "1" smd circle
			(at 0.40005 0 180)
			(size 0 0)
			(layers "B.Cu" "B.Mask" "B.Paste")
			(net "P3V3_AUX")
		)
		(pad "2" smd circle
			(at -0.40005 0 180)
			(size 0 0)
			(layers "B.Cu" "B.Mask" "B.Paste")
			(net "VCCIO0")
		)
	)
	(footprint ""
		(layer "B.Cu")
		(at 41.859454 -65.776094 -90)
		(property "Reference" "R194"
			(at 0 0 90)
			(layer "B.SilkS")
			(hide yes)
			(effects
				(font
					(size 1.27 1.27)
				)
				(justify mirror)
			)
		)
		(property "Value" ""
			(at 0 0 90)
			(layer "B.Fab")
			(effects
				(font
					(size 1.27 1.27)
				)
				(justify mirror)
			)
		)
		(duplicate_pad_numbers_are_jumpers no)
		(fp_line
			(start -0.7874 0.4064)
			(end 0.7874 0.4064)
			(stroke
				(width 0.1524)
				(type default)
			)
			(layer "B.SilkS")
		)
		(fp_line
			(start 0.7874 0.4064)
			(end 0.7874 -0.4064)
			(stroke
				(width 0.1524)
				(type default)
			)
			(layer "B.SilkS")
		)
		(fp_line
			(start -0.7874 -0.4064)
			(end -0.7874 0.4064)
			(stroke
				(width 0.1524)
				(type default)
			)
			(layer "B.SilkS")
		)
		(fp_line
			(start 0.7874 -0.4064)
			(end -0.7874 -0.4064)
			(stroke
				(width 0.1524)
				(type default)
			)
			(layer "B.SilkS")
		)
		(fp_line
			(start -0.67945 0.3048)
			(end -0.120396 0.3048)
			(stroke
				(width 0.1)
				(type default)
			)
			(layer "B.Fab")
		)
		(fp_line
			(start -0.120396 0.3048)
			(end -0.120396 0.2794)
			(stroke
				(width 0.1)
				(type default)
			)
			(layer "B.Fab")
		)
		(fp_line
			(start 0.12065 0.3048)
			(end 0.67945 0.3048)
			(stroke
				(width 0.1)
				(type default)
			)
			(layer "B.Fab")
		)
		(fp_line
			(start 0.67945 0.3048)
			(end 0.67945 -0.305054)
			(stroke
				(width 0.1)
				(type default)
			)
			(layer "B.Fab")
		)
		(fp_line
			(start -0.120396 0.2794)
			(end 0.12065 0.2794)
			(stroke
				(width 0.1)
				(type default)
			)
			(layer "B.Fab")
		)
		(fp_line
			(start 0.12065 0.2794)
			(end 0.12065 0.3048)
			(stroke
				(width 0.1)
				(type default)
			)
			(layer "B.Fab")
		)
		(fp_line
			(start -0.12065 -0.2794)
			(end -0.12065 -0.3048)
			(stroke
				(width 0.1)
				(type default)
			)
			(layer "B.Fab")
		)
		(fp_line
			(start 0.12065 -0.2794)
			(end -0.12065 -0.2794)
			(stroke
				(width 0.1)
				(type default)
			)
			(layer "B.Fab")
		)
		(fp_line
			(start -0.67945 -0.3048)
			(end -0.67945 0.3048)
			(stroke
				(width 0.1)
				(type default)
			)
			(layer "B.Fab")
		)
		(fp_line
			(start -0.12065 -0.3048)
			(end -0.67945 -0.3048)
			(stroke
				(width 0.1)
				(type default)
			)
			(layer "B.Fab")
		)
		(fp_line
			(start 0.12065 -0.305054)
			(end 0.12065 -0.2794)
			(stroke
				(width 0.1)
				(type default)
			)
			(layer "B.Fab")
		)
		(fp_line
			(start 0.67945 -0.305054)
			(end 0.12065 -0.305054)
			(stroke
				(width 0.1)
				(type default)
			)
			(layer "B.Fab")
		)
		(pad "1" smd circle
			(at 0.40005 0 90)
			(size 0 0)
			(layers "B.Cu" "B.Mask" "B.Paste")
			(net "P1V2_P1V0_I3C_VDDL1")
		)
		(pad "2" smd circle
			(at -0.40005 0 90)
			(size 0 0)
			(layers "B.Cu" "B.Mask" "B.Paste")
			(net "I3C1_SPD_SCL")
		)
	)
)
